(kicad_pcb
	(version 20260206)
	(generator "pcbnew")
	(generator_version "10.0")
	(general
		(thickness 1.6)
		(legacy_teardrops no)
	)
	(paper "A4")
	(title_block
		(title "03242023_DA0F0TMBIJ0_F0T_Motherboard_J_brd_V01_OCP.brd")
		(comment 1 "Grand Teton / footprints 4584-4590 of 6105")
	)
	(layers
		(0 "F.Cu" signal "TOP")
		(4 "In1.Cu" signal "GND")
		(6 "In2.Cu" signal "IN1")
		(8 "In3.Cu" signal "GND1")
		(10 "In4.Cu" signal "IN2")
		(12 "In5.Cu" signal "GND2")
		(14 "In6.Cu" signal "IN3")
		(16 "In7.Cu" signal "GND3")
		(18 "In8.Cu" signal "VCC")
		(20 "In9.Cu" signal "VCC1")
		(22 "In10.Cu" signal "GND4")
		(24 "In11.Cu" signal "IN4")
		(26 "In12.Cu" signal "GND5")
		(28 "In13.Cu" signal "IN5")
		(30 "In14.Cu" signal "GND6")
		(32 "In15.Cu" signal "IN6")
		(34 "In16.Cu" signal "GND7")
		(2 "B.Cu" signal "BOTTOM")
		(9 "F.Adhes" user "F.Adhesive")
		(11 "B.Adhes" user "B.Adhesive")
		(13 "F.Paste" user "Package Geometry/Pastemask Top")
		(15 "B.Paste" user "Package Geometry/Pastemask Bottom")
		(5 "F.SilkS" user "Ref Des/Silkscreen Top")
		(7 "B.SilkS" user "Ref Des/Silkscreen Bottom")
		(1 "F.Mask" user "Board Geometry/Soldermask Top")
		(3 "B.Mask" user "Board Geometry/Soldermask Bottom")
		(17 "Dwgs.User" user "User.Drawings")
		(19 "Cmts.User" user "User.Comments")
		(21 "Eco1.User" user "User.Eco1")
		(23 "Eco2.User" user "User.Eco2")
		(25 "Edge.Cuts" user "Board Geometry/Outline")
		(27 "Margin" user)
		(31 "F.CrtYd" user "Package Geometry/Place Bound Top")
		(29 "B.CrtYd" user "Package Geometry/Place Bound Bottom")
		(35 "F.Fab" user "Ref Des/Assembly Top")
		(33 "B.Fab" user "Ref Des/Assembly Bottom")
	)
	(footprint ""
		(layer "B.Cu")
		(at 317.276988 -191.619378 -90)
		(property "Reference" "R4389"
			(at 0 0 90)
			(layer "B.SilkS")
			(hide yes)
			(effects
				(font
					(size 1.27 1.27)
				)
				(justify mirror)
			)
		)
		(property "Value" ""
			(at 0 0 90)
			(layer "B.Fab")
			(effects
				(font
					(size 1.27 1.27)
				)
				(justify mirror)
			)
		)
		(duplicate_pad_numbers_are_jumpers no)
		(fp_line
			(start -0.7874 0.4064)
			(end 0.7874 0.4064)
			(stroke
				(width 0.1524)
				(type default)
			)
			(layer "B.SilkS")
		)
		(fp_line
			(start 0.7874 0.4064)
			(end 0.7874 -0.4064)
			(stroke
				(width 0.1524)
				(type default)
			)
			(layer "B.SilkS")
		)
		(fp_line
			(start -0.7874 -0.4064)
			(end -0.7874 0.4064)
			(stroke
				(width 0.1524)
				(type default)
			)
			(layer "B.SilkS")
		)
		(fp_line
			(start 0.7874 -0.4064)
			(end -0.7874 -0.4064)
			(stroke
				(width 0.1524)
				(type default)
			)
			(layer "B.SilkS")
		)
		(fp_line
			(start -0.67945 0.3048)
			(end -0.120396 0.3048)
			(stroke
				(width 0.1)
				(type default)
			)
			(layer "B.Fab")
		)
		(fp_line
			(start -0.120396 0.3048)
			(end -0.120396 0.2794)
			(stroke
				(width 0.1)
				(type default)
			)
			(layer "B.Fab")
		)
		(fp_line
			(start 0.12065 0.3048)
			(end 0.67945 0.3048)
			(stroke
				(width 0.1)
				(type default)
			)
			(layer "B.Fab")
		)
		(fp_line
			(start 0.67945 0.3048)
			(end 0.67945 -0.305054)
			(stroke
				(width 0.1)
				(type default)
			)
			(layer "B.Fab")
		)
		(fp_line
			(start -0.120396 0.2794)
			(end 0.12065 0.2794)
			(stroke
				(width 0.1)
				(type default)
			)
			(layer "B.Fab")
		)
		(fp_line
			(start 0.12065 0.2794)
			(end 0.12065 0.3048)
			(stroke
				(width 0.1)
				(type default)
			)
			(layer "B.Fab")
		)
		(fp_line
			(start -0.12065 -0.2794)
			(end -0.12065 -0.3048)
			(stroke
				(width 0.1)
				(type default)
			)
			(layer "B.Fab")
		)
		(fp_line
			(start 0.12065 -0.2794)
			(end -0.12065 -0.2794)
			(stroke
				(width 0.1)
				(type default)
			)
			(layer "B.Fab")
		)
		(fp_line
			(start -0.67945 -0.3048)
			(end -0.67945 0.3048)
			(stroke
				(width 0.1)
				(type default)
			)
			(layer "B.Fab")
		)
		(fp_line
			(start -0.12065 -0.3048)
			(end -0.67945 -0.3048)
			(stroke
				(width 0.1)
				(type default)
			)
			(layer "B.Fab")
		)
		(fp_line
			(start 0.12065 -0.305054)
			(end 0.12065 -0.2794)
			(stroke
				(width 0.1)
				(type default)
			)
			(layer "B.Fab")
		)
		(fp_line
			(start 0.67945 -0.305054)
			(end 0.12065 -0.305054)
			(stroke
				(width 0.1)
				(type default)
			)
			(layer "B.Fab")
		)
		(pad "1" smd circle
			(at 0.40005 0 90)
			(size 0 0)
			(layers "B.Cu" "B.Mask" "B.Paste")
			(net "PVNN_TERM_CPU0")
		)
		(pad "2" smd circle
			(at -0.40005 0 90)
			(size 0 0)
			(layers "B.Cu" "B.Mask" "B.Paste")
			(net "H_CPU_ERR2_LVC1_R_N")
		)
	)
	(footprint ""
		(layer "B.Cu")
		(at 229.89032 -127.029718 180)
		(property "Reference" "R2562"
			(at 0 0 0)
			(layer "B.SilkS")
			(hide yes)
			(effects
				(font
					(size 1.27 1.27)
				)
				(justify mirror)
			)
		)
		(property "Value" ""
			(at 0 0 0)
			(layer "B.Fab")
			(effects
				(font
					(size 1.27 1.27)
				)
				(justify mirror)
			)
		)
		(duplicate_pad_numbers_are_jumpers no)
		(fp_line
			(start 0.7874 0.4064)
			(end 0.7874 -0.4064)
			(stroke
				(width 0.1524)
				(type default)
			)
			(layer "B.SilkS")
		)
		(fp_line
			(start 0.7874 -0.4064)
			(end -0.7874 -0.4064)
			(stroke
				(width 0.1524)
				(type default)
			)
			(layer "B.SilkS")
		)
		(fp_line
			(start -0.7874 0.4064)
			(end 0.7874 0.4064)
			(stroke
				(width 0.1524)
				(type default)
			)
			(layer "B.SilkS")
		)
		(fp_line
			(start -0.7874 -0.4064)
			(end -0.7874 0.4064)
			(stroke
				(width 0.1524)
				(type default)
			)
			(layer "B.SilkS")
		)
		(fp_line
			(start 0.67945 0.3048)
			(end 0.67945 -0.305054)
			(stroke
				(width 0.1)
				(type default)
			)
			(layer "B.Fab")
		)
		(fp_line
			(start 0.67945 -0.305054)
			(end 0.12065 -0.305054)
			(stroke
				(width 0.1)
				(type default)
			)
			(layer "B.Fab")
		)
		(fp_line
			(start 0.12065 0.3048)
			(end 0.67945 0.3048)
			(stroke
				(width 0.1)
				(type default)
			)
			(layer "B.Fab")
		)
		(fp_line
			(start 0.12065 0.2794)
			(end 0.12065 0.3048)
			(stroke
				(width 0.1)
				(type default)
			)
			(layer "B.Fab")
		)
		(fp_line
			(start 0.12065 -0.2794)
			(end -0.12065 -0.2794)
			(stroke
				(width 0.1)
				(type default)
			)
			(layer "B.Fab")
		)
		(fp_line
			(start 0.12065 -0.305054)
			(end 0.12065 -0.2794)
			(stroke
				(width 0.1)
				(type default)
			)
			(layer "B.Fab")
		)
		(fp_line
			(start -0.120396 0.3048)
			(end -0.120396 0.2794)
			(stroke
				(width 0.1)
				(type default)
			)
			(layer "B.Fab")
		)
		(fp_line
			(start -0.120396 0.2794)
			(end 0.12065 0.2794)
			(stroke
				(width 0.1)
				(type default)
			)
			(layer "B.Fab")
		)
		(fp_line
			(start -0.12065 -0.2794)
			(end -0.12065 -0.3048)
			(stroke
				(width 0.1)
				(type default)
			)
			(layer "B.Fab")
		)
		(fp_line
			(start -0.12065 -0.3048)
			(end -0.67945 -0.3048)
			(stroke
				(width 0.1)
				(type default)
			)
			(layer "B.Fab")
		)
		(fp_line
			(start -0.67945 0.3048)
			(end -0.120396 0.3048)
			(stroke
				(width 0.1)
				(type default)
			)
			(layer "B.Fab")
		)
		(fp_line
			(start -0.67945 -0.3048)
			(end -0.67945 0.3048)
			(stroke
				(width 0.1)
				(type default)
			)
			(layer "B.Fab")
		)
		(pad "1" smd circle
			(at 0.40005 0)
			(size 0 0)
			(layers "B.Cu" "B.Mask" "B.Paste")
			(net "OCP_SFF_CLK_OE_N")
		)
		(pad "2" smd circle
			(at -0.40005 0)
			(size 0 0)
			(layers "B.Cu" "B.Mask" "B.Paste")
			(net "FM_DB2000_10_OE_N")
		)
	)
	(footprint ""
		(layer "B.Cu")
		(at 193.60388 -104.955848 180)
		(property "Reference" "R1474"
			(at 0 0 0)
			(layer "B.SilkS")
			(hide yes)
			(effects
				(font
					(size 1.27 1.27)
				)
				(justify mirror)
			)
		)
		(property "Value" ""
			(at 0 0 0)
			(layer "B.Fab")
			(effects
				(font
					(size 1.27 1.27)
				)
				(justify mirror)
			)
		)
		(duplicate_pad_numbers_are_jumpers no)
		(fp_line
			(start 0.7874 0.4064)
			(end 0.7874 -0.4064)
			(stroke
				(width 0.1524)
				(type default)
			)
			(layer "B.SilkS")
		)
		(fp_line
			(start 0.7874 -0.4064)
			(end -0.7874 -0.4064)
			(stroke
				(width 0.1524)
				(type default)
			)
			(layer "B.SilkS")
		)
		(fp_line
			(start -0.7874 0.4064)
			(end 0.7874 0.4064)
			(stroke
				(width 0.1524)
				(type default)
			)
			(layer "B.SilkS")
		)
		(fp_line
			(start -0.7874 -0.4064)
			(end -0.7874 0.4064)
			(stroke
				(width 0.1524)
				(type default)
			)
			(layer "B.SilkS")
		)
		(fp_line
			(start 0.67945 0.3048)
			(end 0.67945 -0.305054)
			(stroke
				(width 0.1)
				(type default)
			)
			(layer "B.Fab")
		)
		(fp_line
			(start 0.67945 -0.305054)
			(end 0.12065 -0.305054)
			(stroke
				(width 0.1)
				(type default)
			)
			(layer "B.Fab")
		)
		(fp_line
			(start 0.12065 0.3048)
			(end 0.67945 0.3048)
			(stroke
				(width 0.1)
				(type default)
			)
			(layer "B.Fab")
		)
		(fp_line
			(start 0.12065 0.2794)
			(end 0.12065 0.3048)
			(stroke
				(width 0.1)
				(type default)
			)
			(layer "B.Fab")
		)
		(fp_line
			(start 0.12065 -0.2794)
			(end -0.12065 -0.2794)
			(stroke
				(width 0.1)
				(type default)
			)
			(layer "B.Fab")
		)
		(fp_line
			(start 0.12065 -0.305054)
			(end 0.12065 -0.2794)
			(stroke
				(width 0.1)
				(type default)
			)
			(layer "B.Fab")
		)
		(fp_line
			(start -0.120396 0.3048)
			(end -0.120396 0.2794)
			(stroke
				(width 0.1)
				(type default)
			)
			(layer "B.Fab")
		)
		(fp_line
			(start -0.120396 0.2794)
			(end 0.12065 0.2794)
			(stroke
				(width 0.1)
				(type default)
			)
			(layer "B.Fab")
		)
		(fp_line
			(start -0.12065 -0.2794)
			(end -0.12065 -0.3048)
			(stroke
				(width 0.1)
				(type default)
			)
			(layer "B.Fab")
		)
		(fp_line
			(start -0.12065 -0.3048)
			(end -0.67945 -0.3048)
			(stroke
				(width 0.1)
				(type default)
			)
			(layer "B.Fab")
		)
		(fp_line
			(start -0.67945 0.3048)
			(end -0.120396 0.3048)
			(stroke
				(width 0.1)
				(type default)
			)
			(layer "B.Fab")
		)
		(fp_line
			(start -0.67945 -0.3048)
			(end -0.67945 0.3048)
			(stroke
				(width 0.1)
				(type default)
			)
			(layer "B.Fab")
		)
		(pad "1" smd circle
			(at 0.40005 0)
			(size 0 0)
			(layers "B.Cu" "B.Mask" "B.Paste")
			(net "FM_RST_PERST_BIT2")
		)
		(pad "2" smd circle
			(at -0.40005 0)
			(size 0 0)
			(layers "B.Cu" "B.Mask" "B.Paste")
			(net "P3V3_AUX")
		)
	)
	(footprint ""
		(layer "B.Cu")
		(at 367.898934 -244.820186 -90)
		(property "Reference" "C385"
			(at 0 0 90)
			(layer "B.SilkS")
			(hide yes)
			(effects
				(font
					(size 1.27 1.27)
				)
				(justify mirror)
			)
		)
		(property "Value" ""
			(at 0 0 90)
			(layer "B.Fab")
			(effects
				(font
					(size 1.27 1.27)
				)
				(justify mirror)
			)
		)
		(duplicate_pad_numbers_are_jumpers no)
		(fp_line
			(start -1.524 0.762)
			(end 1.524 0.762)
			(stroke
				(width 0.1524)
				(type default)
			)
			(layer "B.SilkS")
		)
		(fp_line
			(start 1.524 0.762)
			(end 1.524 -0.762)
			(stroke
				(width 0.1524)
				(type default)
			)
			(layer "B.SilkS")
		)
		(fp_line
			(start -1.524 -0.762)
			(end -1.524 0.762)
			(stroke
				(width 0.1524)
				(type default)
			)
			(layer "B.SilkS")
		)
		(fp_line
			(start 1.524 -0.762)
			(end -1.524 -0.762)
			(stroke
				(width 0.1524)
				(type default)
			)
			(layer "B.SilkS")
		)
		(fp_line
			(start -1.1049 0.724916)
			(end -1.1049 -0.724916)
			(stroke
				(width 0.1)
				(type default)
			)
			(layer "B.Fab")
		)
		(fp_line
			(start 1.1049 0.724916)
			(end -1.1049 0.724916)
			(stroke
				(width 0.1)
				(type default)
			)
			(layer "B.Fab")
		)
		(fp_line
			(start -1.1049 -0.724916)
			(end 1.1049 -0.724916)
			(stroke
				(width 0.1)
				(type default)
			)
			(layer "B.Fab")
		)
		(fp_line
			(start 1.1049 -0.724916)
			(end 1.1049 0.724916)
			(stroke
				(width 0.1)
				(type default)
			)
			(layer "B.Fab")
		)
		(pad "1" smd rect
			(at 0.889 0 270)
			(size 1.016 1.27)
			(layers "B.Cu" "B.Mask" "B.Paste")
			(net "PVCCIN_CPU0")
		)
		(pad "2" smd rect
			(at -0.889 0 270)
			(size 1.016 1.27)
			(layers "B.Cu" "B.Mask" "B.Paste")
			(net "GND")
		)
	)
	(footprint ""
		(layer "B.Cu")
		(at 293.053516 -367.168176 180)
		(property "Reference" "PC1671"
			(at 0 0 0)
			(layer "B.SilkS")
			(hide yes)
			(effects
				(font
					(size 1.27 1.27)
				)
				(justify mirror)
			)
		)
		(property "Value" ""
			(at 0 0 0)
			(layer "B.Fab")
			(effects
				(font
					(size 1.27 1.27)
				)
				(justify mirror)
			)
		)
		(duplicate_pad_numbers_are_jumpers no)
		(fp_line
			(start 1.524 0.762)
			(end 1.524 -0.762)
			(stroke
				(width 0.1524)
				(type default)
			)
			(layer "B.SilkS")
		)
		(fp_line
			(start 1.524 -0.762)
			(end -1.524 -0.762)
			(stroke
				(width 0.1524)
				(type default)
			)
			(layer "B.SilkS")
		)
		(fp_line
			(start -1.524 0.762)
			(end 1.524 0.762)
			(stroke
				(width 0.1524)
				(type default)
			)
			(layer "B.SilkS")
		)
		(fp_line
			(start -1.524 -0.762)
			(end -1.524 0.762)
			(stroke
				(width 0.1524)
				(type default)
			)
			(layer "B.SilkS")
		)
		(fp_line
			(start 1.1049 0.724916)
			(end -1.1049 0.724916)
			(stroke
				(width 0.1)
				(type default)
			)
			(layer "B.Fab")
		)
		(fp_line
			(start 1.1049 -0.724916)
			(end 1.1049 0.724916)
			(stroke
				(width 0.1)
				(type default)
			)
			(layer "B.Fab")
		)
		(fp_line
			(start -1.1049 0.724916)
			(end -1.1049 -0.724916)
			(stroke
				(width 0.1)
				(type default)
			)
			(layer "B.Fab")
		)
		(fp_line
			(start -1.1049 -0.724916)
			(end 1.1049 -0.724916)
			(stroke
				(width 0.1)
				(type default)
			)
			(layer "B.Fab")
		)
		(pad "1" smd rect
			(at 0.889 0 180)
			(size 1.016 1.27)
			(layers "B.Cu" "B.Mask" "B.Paste")
			(net "SW_P12V_PVCCFA_EHV_FIVRA_CPU0_L")
		)
		(pad "2" smd rect
			(at -0.889 0 180)
			(size 1.016 1.27)
			(layers "B.Cu" "B.Mask" "B.Paste")
			(net "GND")
		)
	)
	(footprint ""
		(layer "B.Cu")
		(at 172.346112 -8.907018)
		(property "Reference" "R3111"
			(at 0 0 0)
			(layer "B.SilkS")
			(hide yes)
			(effects
				(font
					(size 1.27 1.27)
				)
				(justify mirror)
			)
		)
		(property "Value" ""
			(at 0 0 0)
			(layer "B.Fab")
			(effects
				(font
					(size 1.27 1.27)
				)
				(justify mirror)
			)
		)
		(duplicate_pad_numbers_are_jumpers no)
		(fp_line
			(start -0.7874 -0.4064)
			(end -0.7874 0.4064)
			(stroke
				(width 0.1524)
				(type default)
			)
			(layer "B.SilkS")
		)
		(fp_line
			(start -0.7874 0.4064)
			(end 0.7874 0.4064)
			(stroke
				(width 0.1524)
				(type default)
			)
			(layer "B.SilkS")
		)
		(fp_line
			(start 0.7874 -0.4064)
			(end -0.7874 -0.4064)
			(stroke
				(width 0.1524)
				(type default)
			)
			(layer "B.SilkS")
		)
		(fp_line
			(start 0.7874 0.4064)
			(end 0.7874 -0.4064)
			(stroke
				(width 0.1524)
				(type default)
			)
			(layer "B.SilkS")
		)
		(fp_line
			(start -0.67945 -0.3048)
			(end -0.67945 0.3048)
			(stroke
				(width 0.1)
				(type default)
			)
			(layer "B.Fab")
		)
		(fp_line
			(start -0.67945 0.3048)
			(end -0.120396 0.3048)
			(stroke
				(width 0.1)
				(type default)
			)
			(layer "B.Fab")
		)
		(fp_line
			(start -0.12065 -0.3048)
			(end -0.67945 -0.3048)
			(stroke
				(width 0.1)
				(type default)
			)
			(layer "B.Fab")
		)
		(fp_line
			(start -0.12065 -0.2794)
			(end -0.12065 -0.3048)
			(stroke
				(width 0.1)
				(type default)
			)
			(layer "B.Fab")
		)
		(fp_line
			(start -0.120396 0.2794)
			(end 0.12065 0.2794)
			(stroke
				(width 0.1)
				(type default)
			)
			(layer "B.Fab")
		)
		(fp_line
			(start -0.120396 0.3048)
			(end -0.120396 0.2794)
			(stroke
				(width 0.1)
				(type default)
			)
			(layer "B.Fab")
		)
		(fp_line
			(start 0.12065 -0.305054)
			(end 0.12065 -0.2794)
			(stroke
				(width 0.1)
				(type default)
			)
			(layer "B.Fab")
		)
		(fp_line
			(start 0.12065 -0.2794)
			(end -0.12065 -0.2794)
			(stroke
				(width 0.1)
				(type default)
			)
			(layer "B.Fab")
		)
		(fp_line
			(start 0.12065 0.2794)
			(end 0.12065 0.3048)
			(stroke
				(width 0.1)
				(type default)
			)
			(layer "B.Fab")
		)
		(fp_line
			(start 0.12065 0.3048)
			(end 0.67945 0.3048)
			(stroke
				(width 0.1)
				(type default)
			)
			(layer "B.Fab")
		)
		(fp_line
			(start 0.67945 -0.305054)
			(end 0.12065 -0.305054)
			(stroke
				(width 0.1)
				(type default)
			)
			(layer "B.Fab")
		)
		(fp_line
			(start 0.67945 0.3048)
			(end 0.67945 -0.305054)
			(stroke
				(width 0.1)
				(type default)
			)
			(layer "B.Fab")
		)
		(pad "1" smd circle
			(at 0.40005 0 180)
			(size 0 0)
			(layers "B.Cu" "B.Mask" "B.Paste")
			(net "I3C_BMC_SWB_SDA")
		)
		(pad "2" smd circle
			(at -0.40005 0 180)
			(size 0 0)
			(layers "B.Cu" "B.Mask" "B.Paste")
			(net "I3C_BMC_SWB_R_SDA")
		)
	)
	(footprint ""
		(layer "B.Cu")
		(at 38.09746 -357.575612)
		(property "Reference" "PR1334"
			(at 0 0 0)
			(layer "B.SilkS")
			(hide yes)
			(effects
				(font
					(size 1.27 1.27)
				)
				(justify mirror)
			)
		)
		(property "Value" ""
			(at 0 0 0)
			(layer "B.Fab")
			(effects
				(font
					(size 1.27 1.27)
				)
				(justify mirror)
			)
		)
		(duplicate_pad_numbers_are_jumpers no)
		(fp_line
			(start -0.7874 -0.4064)
			(end -0.7874 0.4064)
			(stroke
				(width 0.1524)
				(type default)
			)
			(layer "B.SilkS")
		)
		(fp_line
			(start -0.7874 0.4064)
			(end 0.7874 0.4064)
			(stroke
				(width 0.1524)
				(type default)
			)
			(layer "B.SilkS")
		)
		(fp_line
			(start 0.7874 -0.4064)
			(end -0.7874 -0.4064)
			(stroke
				(width 0.1524)
				(type default)
			)
			(layer "B.SilkS")
		)
		(fp_line
			(start 0.7874 0.4064)
			(end 0.7874 -0.4064)
			(stroke
				(width 0.1524)
				(type default)
			)
			(layer "B.SilkS")
		)
		(fp_line
			(start -0.67945 -0.3048)
			(end -0.67945 0.3048)
			(stroke
				(width 0.1)
				(type default)
			)
			(layer "B.Fab")
		)
		(fp_line
			(start -0.67945 0.3048)
			(end -0.120396 0.3048)
			(stroke
				(width 0.1)
				(type default)
			)
			(layer "B.Fab")
		)
		(fp_line
			(start -0.12065 -0.3048)
			(end -0.67945 -0.3048)
			(stroke
				(width 0.1)
				(type default)
			)
			(layer "B.Fab")
		)
		(fp_line
			(start -0.12065 -0.2794)
			(end -0.12065 -0.3048)
			(stroke
				(width 0.1)
				(type default)
			)
			(layer "B.Fab")
		)
		(fp_line
			(start -0.120396 0.2794)
			(end 0.12065 0.2794)
			(stroke
				(width 0.1)
				(type default)
			)
			(layer "B.Fab")
		)
		(fp_line
			(start -0.120396 0.3048)
			(end -0.120396 0.2794)
			(stroke
				(width 0.1)
				(type default)
			)
			(layer "B.Fab")
		)
		(fp_line
			(start 0.12065 -0.305054)
			(end 0.12065 -0.2794)
			(stroke
				(width 0.1)
				(type default)
			)
			(layer "B.Fab")
		)
		(fp_line
			(start 0.12065 -0.2794)
			(end -0.12065 -0.2794)
			(stroke
				(width 0.1)
				(type default)
			)
			(layer "B.Fab")
		)
		(fp_line
			(start 0.12065 0.2794)
			(end 0.12065 0.3048)
			(stroke
				(width 0.1)
				(type default)
			)
			(layer "B.Fab")
		)
		(fp_line
			(start 0.12065 0.3048)
			(end 0.67945 0.3048)
			(stroke
				(width 0.1)
				(type default)
			)
			(layer "B.Fab")
		)
		(fp_line
			(start 0.67945 -0.305054)
			(end 0.12065 -0.305054)
			(stroke
				(width 0.1)
				(type default)
			)
			(layer "B.Fab")
		)
		(fp_line
			(start 0.67945 0.3048)
			(end 0.67945 -0.305054)
			(stroke
				(width 0.1)
				(type default)
			)
			(layer "B.Fab")
		)
		(pad "1" smd circle
			(at 0.40005 0 180)
			(size 0 0)
			(layers "B.Cu" "B.Mask" "B.Paste")
			(net "PVCCFA_EHV_FIVRA_CPU1_VOS4")
		)
		(pad "2" smd circle
			(at -0.40005 0 180)
			(size 0 0)
			(layers "B.Cu" "B.Mask" "B.Paste")
			(net "PVCCFA_EHV_FIVRA_CPU1")
		)
	)
)
